(kicad_pcb
	(version 20260206)
	(generator "pcbnew")
	(generator_version "10.0")
	(general
		(thickness 1.6)
		(legacy_teardrops no)
	)
	(paper "A4")
	(title_block
		(title "Bryce Canyon_R.DPB_16317-1_OCP.brd")
		(comment 1 "Bryce Canyon / footprints 321-323 of 2099")
	)
	(layers
		(0 "F.Cu" signal "TOP")
		(4 "In1.Cu" signal "L2GND")
		(6 "In2.Cu" signal "L3")
		(8 "In3.Cu" signal "L4VCC")
		(10 "In4.Cu" signal "L5VCC")
		(12 "In5.Cu" signal "L6")
		(14 "In6.Cu" signal "L7GND")
		(2 "B.Cu" signal "BOTTOM")
		(9 "F.Adhes" user "F.Adhesive")
		(11 "B.Adhes" user "B.Adhesive")
		(13 "F.Paste" user "Package Geometry/Pastemask Top")
		(15 "B.Paste" user "Package Geometry/Pastemask Bottom")
		(5 "F.SilkS" user "Ref Des/Silkscreen Top")
		(7 "B.SilkS" user "Ref Des/Silkscreen Bottom")
		(1 "F.Mask" user "Board Geometry/Soldermask Top")
		(3 "B.Mask" user "Board Geometry/Soldermask Bottom")
		(17 "Dwgs.User" user "User.Drawings")
		(19 "Cmts.User" user "User.Comments")
		(21 "Eco1.User" user "User.Eco1")
		(23 "Eco2.User" user "User.Eco2")
		(25 "Edge.Cuts" user "Board Geometry/Outline")
		(27 "Margin" user)
		(31 "F.CrtYd" user "Package Geometry/Place Bound Top")
		(29 "B.CrtYd" user "Package Geometry/Place Bound Bottom")
		(35 "F.Fab" user "Ref Des/Assembly Top")
		(33 "B.Fab" user "Ref Des/Assembly Bottom")
	)
	(footprint ""
		(layer "F.Cu")
		(at 130.302 -151.003 90)
		(property "Reference" "R419"
			(at 0 0 90)
			(layer "F.SilkS")
			(hide yes)
			(effects
				(font
					(size 1.27 1.27)
				)
			)
		)
		(property "Value" "220R3F-1-GP"
			(at -0.0254 -2.5146 90)
			(unlocked yes)
			(layer "F.Fab")
			(hide yes)
			(effects
				(font
					(size 1.016 1.016)
					(thickness 0.1524)
				)
			)
		)
		(property "Device Type" "R603H22"
			(at -0.0254 -4.0386 90)
			(unlocked yes)
			(layer "F.Fab")
			(hide yes)
			(effects
				(font
					(size 1.016 1.016)
					(thickness 0.1524)
				)
			)
		)
		(duplicate_pad_numbers_are_jumpers no)
		(fp_line
			(start 0.2032 0)
			(end 0.4826 0)
			(stroke
				(width 0.2032)
				(type default)
			)
			(layer "F.SilkS")
		)
		(fp_line
			(start -0.4826 0)
			(end -0.2032 0)
			(stroke
				(width 0.2032)
				(type default)
			)
			(layer "F.SilkS")
		)
		(fp_rect
			(start -0.5842 1.3335)
			(end 0.5842 -1.3335)
			(stroke
				(width 0)
				(type default)
			)
			(fill no)
			(layer "F.CrtYd")
		)
		(fp_rect
			(start -0.5842 1.3335)
			(end 0.5842 -1.3335)
			(stroke
				(width 0)
				(type default)
			)
			(fill no)
			(layer "F.Fab")
		)
		(pad "1" smd custom
			(at 0 -0.762 90)
			(size 0.2159 0.2159)
			(layers "F.Cu" "F.Mask" "F.Paste")
			(net "HDD_PRSNT_15")
			(options
				(clearance outline)
				(anchor circle)
			)
			(primitives
				(gr_poly
					(pts
						(arc
							(start -0.3302 -0.4318)
							(mid -0.402042 -0.402042)
							(end -0.4318 -0.3302)
						)
						(arc
							(start -0.4318 0.3302)
							(mid -0.402042 0.402042)
							(end -0.3302 0.4318)
						)
						(arc
							(start 0.3302 0.4318)
							(mid 0.402042 0.402042)
							(end 0.4318 0.3302)
						)
						(arc
							(start 0.4318 -0.3302)
							(mid 0.402042 -0.402042)
							(end 0.3302 -0.4318)
						)
					)
					(width 0)
					(fill yes)
				)
			)
		)
		(pad "2" smd custom
			(at 0 0.762 90)
			(size 0.2159 0.2159)
			(layers "F.Cu" "F.Mask" "F.Paste")
			(net "DRIVE_B_15_INS")
			(options
				(clearance outline)
				(anchor circle)
			)
			(primitives
				(gr_poly
					(pts
						(arc
							(start -0.3302 -0.4318)
							(mid -0.402042 -0.402042)
							(end -0.4318 -0.3302)
						)
						(arc
							(start -0.4318 0.3302)
							(mid -0.402042 0.402042)
							(end -0.3302 0.4318)
						)
						(arc
							(start 0.3302 0.4318)
							(mid 0.402042 0.402042)
							(end 0.4318 0.3302)
						)
						(arc
							(start 0.4318 -0.3302)
							(mid 0.402042 -0.402042)
							(end 0.3302 -0.4318)
						)
					)
					(width 0)
					(fill yes)
				)
			)
		)
	)
	(footprint ""
		(layer "F.Cu")
		(at 98.806 -266.065 90)
		(property "Reference" "R193"
			(at 0 0 90)
			(layer "F.SilkS")
			(hide yes)
			(effects
				(font
					(size 1.27 1.27)
				)
			)
		)
		(property "Value" "220R3F-1-GP"
			(at -0.0254 -2.5146 90)
			(unlocked yes)
			(layer "F.Fab")
			(hide yes)
			(effects
				(font
					(size 1.016 1.016)
					(thickness 0.1524)
				)
			)
		)
		(property "Device Type" "R603H22"
			(at -0.0254 -4.0386 90)
			(unlocked yes)
			(layer "F.Fab")
			(hide yes)
			(effects
				(font
					(size 1.016 1.016)
					(thickness 0.1524)
				)
			)
		)
		(duplicate_pad_numbers_are_jumpers no)
		(fp_line
			(start 0.2032 0)
			(end 0.4826 0)
			(stroke
				(width 0.2032)
				(type default)
			)
			(layer "F.SilkS")
		)
		(fp_line
			(start -0.4826 0)
			(end -0.2032 0)
			(stroke
				(width 0.2032)
				(type default)
			)
			(layer "F.SilkS")
		)
		(fp_rect
			(start -0.5842 1.3335)
			(end 0.5842 -1.3335)
			(stroke
				(width 0)
				(type default)
			)
			(fill no)
			(layer "F.CrtYd")
		)
		(fp_rect
			(start -0.5842 1.3335)
			(end 0.5842 -1.3335)
			(stroke
				(width 0)
				(type default)
			)
			(fill no)
			(layer "F.Fab")
		)
		(pad "1" smd custom
			(at 0 -0.762 90)
			(size 0.2159 0.2159)
			(layers "F.Cu" "F.Mask" "F.Paste")
			(net "HDD_PRSNT_2")
			(options
				(clearance outline)
				(anchor circle)
			)
			(primitives
				(gr_poly
					(pts
						(arc
							(start -0.3302 -0.4318)
							(mid -0.402042 -0.402042)
							(end -0.4318 -0.3302)
						)
						(arc
							(start -0.4318 0.3302)
							(mid -0.402042 0.402042)
							(end -0.3302 0.4318)
						)
						(arc
							(start 0.3302 0.4318)
							(mid 0.402042 0.402042)
							(end 0.4318 0.3302)
						)
						(arc
							(start 0.4318 -0.3302)
							(mid 0.402042 -0.402042)
							(end 0.3302 -0.4318)
						)
					)
					(width 0)
					(fill yes)
				)
			)
		)
		(pad "2" smd custom
			(at 0 0.762 90)
			(size 0.2159 0.2159)
			(layers "F.Cu" "F.Mask" "F.Paste")
			(net "DRIVE_B_2_INS")
			(options
				(clearance outline)
				(anchor circle)
			)
			(primitives
				(gr_poly
					(pts
						(arc
							(start -0.3302 -0.4318)
							(mid -0.402042 -0.402042)
							(end -0.4318 -0.3302)
						)
						(arc
							(start -0.4318 0.3302)
							(mid -0.402042 0.402042)
							(end -0.3302 0.4318)
						)
						(arc
							(start 0.3302 0.4318)
							(mid 0.402042 0.402042)
							(end 0.4318 0.3302)
						)
						(arc
							(start 0.4318 -0.3302)
							(mid 0.402042 -0.402042)
							(end 0.3302 -0.4318)
						)
					)
					(width 0)
					(fill yes)
				)
			)
		)
	)
	(footprint ""
		(layer "F.Cu")
		(at 59.749944 -28.910026 -90)
		(property "Reference" "HDDSAS25"
			(at 0 0 270)
			(layer "F.SilkS")
			(hide yes)
			(effects
				(font
					(size 1.27 1.27)
				)
			)
		)
		(property "Value" "SKT-SAS15P-14P-45-GP"
			(at -20.7645 -8.9789 270)
			(unlocked yes)
			(layer "F.Fab")
			(hide yes)
			(effects
				(font
					(size 1.016 1.016)
					(thickness 0.1524)
				)
			)
		)
		(property "Device Type" "10120818-001C-TRLF"
			(at -20.7645 -10.5029 270)
			(unlocked yes)
			(layer "F.Fab")
			(hide yes)
			(effects
				(font
					(size 1.016 1.016)
					(thickness 0.1524)
				)
			)
		)
		(duplicate_pad_numbers_are_jumpers no)
		(fp_line
			(start 1.651 4.2926)
			(end 1.651 3.0099)
			(stroke
				(width 0.1524)
				(type default)
			)
			(layer "F.SilkS")
		)
		(fp_line
			(start 8.509 4.2926)
			(end 1.651 4.2926)
			(stroke
				(width 0.1524)
				(type default)
			)
			(layer "F.SilkS")
		)
		(fp_line
			(start -23.4188 3.0099)
			(end -23.4188 -3.2512)
			(stroke
				(width 0.1524)
				(type default)
			)
			(layer "F.SilkS")
		)
		(fp_line
			(start 1.651 3.0099)
			(end -23.4188 3.0099)
			(stroke
				(width 0.1524)
				(type default)
			)
			(layer "F.SilkS")
		)
		(fp_line
			(start 8.509 3.0099)
			(end 8.509 4.2926)
			(stroke
				(width 0.1524)
				(type default)
			)
			(layer "F.SilkS")
		)
		(fp_line
			(start 23.4188 3.0099)
			(end 8.509 3.0099)
			(stroke
				(width 0.1524)
				(type default)
			)
			(layer "F.SilkS")
		)
		(fp_line
			(start -23.4188 -3.2512)
			(end 23.4188 -3.2512)
			(stroke
				(width 0.1524)
				(type default)
			)
			(layer "F.SilkS")
		)
		(fp_line
			(start 23.4188 -3.2512)
			(end 23.4188 3.0099)
			(stroke
				(width 0.1524)
				(type default)
			)
			(layer "F.SilkS")
		)
		(fp_line
			(start 15.5067 -3.3401)
			(end 16.2687 -3.3401)
			(stroke
				(width 0.3302)
				(type default)
			)
			(layer "F.SilkS")
		)
		(fp_poly
			(pts
				(xy 15.868904 -3.230372) (xy 16.503904 -3.865372) (xy 15.233904 -3.865372)
			)
			(stroke
				(width 0)
				(type default)
			)
			(fill yes)
			(layer "F.SilkS")
		)
		(fp_poly
			(pts
				(xy -22.8727 -2.7559) (xy 22.8727 -2.7559) (xy 22.8727 2.7559) (xy 8.255 2.7559) (xy 8.255 3.5179)
				(xy 1.905 3.5179) (xy 1.905 2.7559) (xy -22.8727 2.7559)
			)
			(stroke
				(width 0)
				(type default)
			)
			(fill no)
			(layer "F.CrtYd")
		)
		(fp_poly
			(pts
				(xy 1.397 4.5466) (xy 1.397 3.2639) (xy -23.6728 3.2639) (xy -23.6728 -3.5052) (xy 23.6728 -3.5052)
				(xy 23.6728 -0.00635) (xy 22.8727 -0.00635) (xy 22.8727 -2.7559) (xy -22.8727 -2.7559) (xy -22.8727 2.7559)
				(xy 1.905 2.7559) (xy 1.905 3.5179) (xy 8.255 3.5179) (xy 8.255 2.7559) (xy 22.8727 2.7559) (xy 22.8727 0.00635)
				(xy 23.6728 0.00635) (xy 23.6728 3.2639) (xy 8.763 3.2639) (xy 8.763 4.5466)
			)
			(stroke
				(width 0)
				(type default)
			)
			(fill no)
			(layer "F.CrtYd")
		)
		(fp_poly
			(pts
				(xy 1.397 4.5466) (xy 1.397 3.2639) (xy -23.6728 3.2639) (xy -23.6728 -3.5052) (xy 23.6728 -3.5052)
				(xy 23.6728 3.2639) (xy 8.763 3.2639) (xy 8.763 4.5466)
			)
			(stroke
				(width 0)
				(type default)
			)
			(fill no)
			(layer "F.Fab")
		)
		(pad "" np_thru_hole circle
			(at -18.874994 0 270)
			(size 0.254 0.254)
			(drill 1.3462)
			(layers "*.Cu" "*.Mask")
			(clearance 0.9017)
			(thermal_gap 0.9017)
		)
		(pad "" np_thru_hole circle
			(at 18.874994 0 270)
			(size 0.254 0.254)
			(drill 0.9398)
			(layers "*.Cu" "*.Mask")
			(clearance 0.6985)
			(thermal_gap 0.6985)
		)
		(pad "G1" smd rect
			(at 21.874988 0 270)
			(size 2.5908 2.5908)
			(layers "F.Cu" "F.Mask" "F.Paste")
			(net "GND")
		)
		(pad "G2" smd rect
			(at -21.874988 0 270)
			(size 2.5908 2.5908)
			(layers "F.Cu" "F.Mask" "F.Paste")
			(net "GND")
		)
		(pad "P1" smd rect
			(at 1.905 -1.82499 270)
			(size 0.6096 2.3622)
			(layers "F.Cu" "F.Mask" "F.Paste")
			(net "Net_1674")
		)
		(pad "P2" smd rect
			(at 0.635 -1.82499 270)
			(size 0.6096 2.3622)
			(layers "F.Cu" "F.Mask" "F.Paste")
			(net "Net_1675")
		)
		(pad "P3" smd rect
			(at -0.635 -1.82499 270)
			(size 0.6096 2.3622)
			(layers "F.Cu" "F.Mask" "F.Paste")
			(net "Net_1676")
		)
		(pad "P4" smd rect
			(at -1.905 -1.82499 270)
			(size 0.6096 2.3622)
			(layers "F.Cu" "F.Mask" "F.Paste")
			(net "GND")
		)
		(pad "P5" smd rect
			(at -3.175 -1.82499 270)
			(size 0.6096 2.3622)
			(layers "F.Cu" "F.Mask" "F.Paste")
			(net "HDD_PRSNT_25")
		)
		(pad "P6" smd rect
			(at -4.445 -1.82499 270)
			(size 0.6096 2.3622)
			(layers "F.Cu" "F.Mask" "F.Paste")
			(net "GND")
		)
		(pad "P7" smd rect
			(at -5.715 -1.82499 270)
			(size 0.6096 2.3622)
			(layers "F.Cu" "F.Mask" "F.Paste")
			(net "5V_PRE_25")
		)
		(pad "P8" smd rect
			(at -6.985 -1.82499 270)
			(size 0.6096 2.3622)
			(layers "F.Cu" "F.Mask" "F.Paste")
			(net "P5V_HDD25")
		)
		(pad "P9" smd rect
			(at -8.255 -1.82499 270)
			(size 0.6096 2.3622)
			(layers "F.Cu" "F.Mask" "F.Paste")
			(net "P5V_HDD25")
		)
		(pad "P10" smd rect
			(at -9.525 -1.82499 270)
			(size 0.6096 2.3622)
			(layers "F.Cu" "F.Mask" "F.Paste")
			(net "GND")
		)
		(pad "P11" smd rect
			(at -10.795 -1.82499 270)
			(size 0.6096 2.3622)
			(layers "F.Cu" "F.Mask" "F.Paste")
			(net "ACT_HDD_25")
		)
		(pad "P12" smd rect
			(at -12.065 -1.82499 270)
			(size 0.6096 2.3622)
			(layers "F.Cu" "F.Mask" "F.Paste")
			(net "GND")
		)
		(pad "P13" smd rect
			(at -13.335 -1.82499 270)
			(size 0.6096 2.3622)
			(layers "F.Cu" "F.Mask" "F.Paste")
			(net "12V_PRE_25")
		)
		(pad "P14" smd rect
			(at -14.605 -1.82499 270)
			(size 0.6096 2.3622)
			(layers "F.Cu" "F.Mask" "F.Paste")
			(net "P12V_HDD25")
		)
		(pad "P15" smd rect
			(at -15.875 -1.82499 270)
			(size 0.6096 2.3622)
			(layers "F.Cu" "F.Mask" "F.Paste")
			(net "P12V_HDD25")
		)
		(pad "S1" smd rect
			(at 15.875 -1.82499 270)
			(size 0.6096 2.3622)
			(layers "F.Cu" "F.Mask" "F.Paste")
			(net "GND")
		)
		(pad "S2" smd rect
			(at 14.605 -1.82499 270)
			(size 0.6096 2.3622)
			(layers "F.Cu" "F.Mask" "F.Paste")
			(net "SAS_HDD_RX_P25")
		)
		(pad "S3" smd rect
			(at 13.335 -1.82499 270)
			(size 0.6096 2.3622)
			(layers "F.Cu" "F.Mask" "F.Paste")
			(net "SAS_HDD_RX_N25")
		)
		(pad "S4" smd rect
			(at 12.065 -1.82499 270)
			(size 0.6096 2.3622)
			(layers "F.Cu" "F.Mask" "F.Paste")
			(net "GND")
		)
		(pad "S5" smd rect
			(at 10.795 -1.82499 270)
			(size 0.6096 2.3622)
			(layers "F.Cu" "F.Mask" "F.Paste")
			(net "PHY_DRV_B_TO_SCC_B_25_DN")
		)
		(pad "S6" smd rect
			(at 9.525 -1.82499 270)
			(size 0.6096 2.3622)
			(layers "F.Cu" "F.Mask" "F.Paste")
			(net "PHY_DRV_B_TO_SCC_B_25_DP")
		)
		(pad "S7" smd rect
			(at 8.255 -1.82499 270)
			(size 0.6096 2.3622)
			(layers "F.Cu" "F.Mask" "F.Paste")
			(net "GND")
		)
		(pad "S8" smd rect
			(at 7.480046 2.845054 270)
			(size 0.508 2.3622)
			(layers "F.Cu" "F.Mask" "F.Paste")
			(net "GND")
		)
		(pad "S9" smd rect
			(at 6.679946 2.845054 270)
			(size 0.508 2.3622)
			(layers "F.Cu" "F.Mask" "F.Paste")
			(net "Net_449")
		)
		(pad "S10" smd rect
			(at 5.8801 2.845054 270)
			(size 0.508 2.3622)
			(layers "F.Cu" "F.Mask" "F.Paste")
			(net "Net_341")
		)
		(pad "S11" smd rect
			(at 5.08 2.845054 270)
			(size 0.508 2.3622)
			(layers "F.Cu" "F.Mask" "F.Paste")
			(net "GND")
		)
		(pad "S12" smd rect
			(at 4.2799 2.845054 270)
			(size 0.508 2.3622)
			(layers "F.Cu" "F.Mask" "F.Paste")
			(net "Net_377")
		)
		(pad "S13" smd rect
			(at 3.480054 2.845054 270)
			(size 0.508 2.3622)
			(layers "F.Cu" "F.Mask" "F.Paste")
			(net "Net_413")
		)
		(pad "S14" smd rect
			(at 2.679954 2.845054 270)
			(size 0.508 2.3622)
			(layers "F.Cu" "F.Mask" "F.Paste")
			(net "GND")
		)
		(zone
			(layer "F.Cu")
			(hatch none 0.5)
			(connect_pads
				(clearance 0)
			)
			(min_thickness 0.25)
			(keepout
				(tracks allowed)
				(vias not_allowed)
				(pads allowed)
				(copperpour not_allowed)
				(footprints allowed)
			)
			(placement
				(enabled no)
				(sheetname "")
			)
			(fill
				(thermal_gap 0.5)
				(thermal_bridge_width 0.5)
				(island_removal_mode 0)
			)
			(polygon
				(pts
					(xy 63.407544 -45.648626) (xy 56.333644 -45.648626) (xy 56.333644 -52.582826) (xy 57.438544 -52.582826)
					(xy 57.438544 -48.468026) (xy 62.061344 -48.468026) (xy 62.061344 -52.582826) (xy 63.407544 -52.582826)
				)
			)
		)
		(zone
			(layer "F.Cu")
			(hatch none 0.5)
			(connect_pads
				(clearance 0)
			)
			(min_thickness 0.25)
			(keepout
				(tracks not_allowed)
				(vias allowed)
				(pads allowed)
				(copperpour not_allowed)
				(footprints allowed)
			)
			(placement
				(enabled no)
				(sheetname "")
			)
			(fill
				(thermal_gap 0.5)
				(thermal_bridge_width 0.5)
				(island_removal_mode 0)
			)
			(polygon
				(pts
					(xy 63.407544 -45.648626) (xy 56.333644 -45.648626) (xy 56.333644 -52.582826) (xy 57.438544 -52.582826)
					(xy 57.438544 -48.468026) (xy 62.061344 -48.468026) (xy 62.061344 -52.582826) (xy 63.407544 -52.582826)
				)
			)
		)
		(zone
			(layer "F.Cu")
			(hatch none 0.5)
			(connect_pads
				(clearance 0)
			)
			(min_thickness 0.25)
			(keepout
				(tracks allowed)
				(vias not_allowed)
				(pads allowed)
				(copperpour not_allowed)
				(footprints allowed)
			)
			(placement
				(enabled no)
				(sheetname "")
			)
			(fill
				(thermal_gap 0.5)
				(thermal_bridge_width 0.5)
				(island_removal_mode 0)
			)
			(polygon
				(pts
					(xy 63.407544 -12.171426) (xy 56.333644 -12.171426) (xy 56.333644 -5.237226) (xy 57.438544 -5.237226)
					(xy 57.438544 -9.352026) (xy 62.061344 -9.352026) (xy 62.061344 -5.237226) (xy 63.407544 -5.237226)
				)
			)
		)
		(zone
			(layer "F.Cu")
			(hatch none 0.5)
			(connect_pads
				(clearance 0)
			)
			(min_thickness 0.25)
			(keepout
				(tracks not_allowed)
				(vias allowed)
				(pads allowed)
				(copperpour not_allowed)
				(footprints allowed)
			)
			(placement
				(enabled no)
				(sheetname "")
			)
			(fill
				(thermal_gap 0.5)
				(thermal_bridge_width 0.5)
				(island_removal_mode 0)
			)
			(polygon
				(pts
					(xy 63.407544 -12.171426) (xy 56.333644 -12.171426) (xy 56.333644 -5.237226) (xy 57.438544 -5.237226)
					(xy 57.438544 -9.352026) (xy 62.061344 -9.352026) (xy 62.061344 -5.237226) (xy 63.407544 -5.237226)
				)
			)
		)
		(zone
			(layers "F.Cu" "B.Cu" "In1.Cu" "In2.Cu" "In3.Cu" "In4.Cu" "In5.Cu" "In6.Cu")
			(hatch none 0.5)
			(connect_pads
				(clearance 0)
			)
			(min_thickness 0.25)
			(keepout
				(tracks not_allowed)
				(vias allowed)
				(pads allowed)
				(copperpour not_allowed)
				(footprints allowed)
			)
			(placement
				(enabled no)
				(sheetname "")
			)
			(fill
				(thermal_gap 0.5)
				(thermal_bridge_width 0.5)
				(island_removal_mode 0)
			)
			(polygon
				(pts
					(arc
						(start 60.524644 -10.035032)
						(mid 58.975244 -10.035032)
						(end 60.524644 -10.035032)
					)
				)
			)
		)
		(zone
			(layers "F.Cu" "B.Cu" "In1.Cu" "In2.Cu" "In3.Cu" "In4.Cu" "In5.Cu" "In6.Cu")
			(hatch none 0.5)
			(connect_pads
				(clearance 0)
			)
			(min_thickness 0.25)
			(keepout
				(tracks not_allowed)
				(vias allowed)
				(pads allowed)
				(copperpour not_allowed)
				(footprints allowed)
			)
			(placement
				(enabled no)
				(sheetname "")
			)
			(fill
				(thermal_gap 0.5)
				(thermal_bridge_width 0.5)
				(island_removal_mode 0)
			)
			(polygon
				(pts
					(arc
						(start 60.727844 -47.78502)
						(mid 58.772044 -47.78502)
						(end 60.727844 -47.78502)
					)
				)
			)
		)
	)
)
